# BASEBOARD_FAB2 (Tioga Pass) — schematic netlist excerpt (pin names and nets, part order shuffled) for the footprints in the layout excerpt that follows; sources: Cadence DE-HDL packaged netlist, KiCad conversion of Wiwynn_Tioga_Pass_MB.brd

CONX8  SMC-CONN60A-22-GP  pkg CONN-G7  page 245
  \1\  = GND
  \2\  = NC
  \3\  = P3E_CPU0_PE2_SS_C_TXN<8>
  \4\  = GND
  \5\  = P3E_CPU0_PE2_SS_C_TXP<8>
  \6\  = P3E_CPU0_PE2_SS_RXN<8>
  \7\  = GND
  \8\  = P3E_CPU0_PE2_SS_RXP<8>
  \9\  = P3E_CPU0_PE2_SS_C_TXN<9>
  \10\  = GND
  \11\  = P3E_CPU0_PE2_SS_C_TXP<9>
  \12\  = P3E_CPU0_PE2_SS_RXN<9>
  \13\  = GND
  \14\  = P3E_CPU0_PE2_SS_RXP<9>
  \15\  = P3E_CPU0_PE2_SS_C_TXN<10>
  \16\  = GND
  \17\  = P3E_CPU0_PE2_SS_C_TXP<10>
  \18\  = P3E_CPU0_PE2_SS_RXN<10>
  \19\  = GND
  \20\  = P3E_CPU0_PE2_SS_RXP<10>
  \21\  = P3E_CPU0_PE2_SS_C_TXP<11>
  \22\  = GND
  \23\  = P3E_CPU0_PE2_SS_C_TXN<11>
  \24\  = P3E_CPU0_PE2_SS_RXN<11>
  \25\  = GND
  \26\  = P3E_CPU0_PE2_SS_RXP<11>
  \27\  = P3E_CPU0_PE2_SS_C_TXN<12>
  \28\  = GND
  \29\  = P3E_CPU0_PE2_SS_C_TXP<12>
  \30\  = P3E_CPU0_PE2_SS_RXN<12>
  \31\  = GND
  \32\  = P3E_CPU0_PE2_SS_RXP<12>
  \33\  = P3E_CPU0_PE2_SS_C_TXN<13>
  \34\  = GND
  \35\  = P3E_CPU0_PE2_SS_C_TXP<13>
  \36\  = P3E_CPU0_PE2_SS_RXP<13>
  \37\  = GND
  \38\  = P3E_CPU0_PE2_SS_RXN<13>
  \39\  = P3E_CPU0_PE2_SS_C_TXP<14>
  \40\  = GND
  \41\  = P3E_CPU0_PE2_SS_C_TXN<14>
  \42\  = P3E_CPU0_PE2_SS_RXN<14>
  \43\  = GND
  \44\  = P3E_CPU0_PE2_SS_RXP<14>
  \45\  = P3E_CPU0_PE2_SS_C_TXN<15>
  \46\  = GND
  \47\  = P3E_CPU0_PE2_SS_C_TXP<15>
  \48\  = P3E_CPU0_PE2_SS_RXN<15>
  \49\  = GND
  \50\  = P3E_CPU0_PE2_SS_RXP<15>
  \51\  = JTAG_RISER_TDI
  \52\  = GND
  \53\  = JTAG_RISER_TDO
  \54\  = JTAG_RISER_TMS
  \55\  = GND
  \56\  = JTAG_RISER_TCK
  \57\  = USB2_P02_DN
  \58\  = GND
  \59\  = USB2_P02_DP
  \60\  = JTAG_RISER_TRST
  NP1  = NC
  NP2  = NC
  PTH1  = GND
  PTH2  = GND

(kicad_pcb
	(version 20260206)
	(generator "pcbnew")
	(generator_version "10.0")
	(general
		(thickness 1.6)
		(legacy_teardrops no)
	)
	(paper "A4")
	(title_block
		(title "Wiwynn_Tioga_Pass_MB.brd")
		(comment 1 "Tioga Pass / footprint 865 of 4770 (CONX8), pads 1-43 of 64")
	)
	(layers
		(0 "F.Cu" signal "TOP")
		(4 "In1.Cu" signal "L2GND")
		(6 "In2.Cu" signal "L3")
		(8 "In3.Cu" signal "L4GND")
		(10 "In4.Cu" signal "L5")
		(12 "In5.Cu" signal "L6GND")
		(14 "In6.Cu" signal "L7VCC")
		(16 "In7.Cu" signal "L8VCC")
		(18 "In8.Cu" signal "L9GND")
		(20 "In9.Cu" signal "L10")
		(22 "In10.Cu" signal "L11GND")
		(24 "In11.Cu" signal "L12")
		(26 "In12.Cu" signal "L13GND")
		(2 "B.Cu" signal "BOTTOM")
		(9 "F.Adhes" user "F.Adhesive")
		(11 "B.Adhes" user "B.Adhesive")
		(13 "F.Paste" user "Package Geometry/Pastemask Top")
		(15 "B.Paste" user "Package Geometry/Pastemask Bottom")
		(5 "F.SilkS" user "Ref Des/Silkscreen Top")
		(7 "B.SilkS" user "Ref Des/Silkscreen Bottom")
		(1 "F.Mask" user "Board Geometry/Soldermask Top")
		(3 "B.Mask" user "Board Geometry/Soldermask Bottom")
		(17 "Dwgs.User" user "User.Drawings")
		(19 "Cmts.User" user "User.Comments")
		(21 "Eco1.User" user "User.Eco1")
		(23 "Eco2.User" user "User.Eco2")
		(25 "Edge.Cuts" user "Board Geometry/Outline")
		(27 "Margin" user)
		(31 "F.CrtYd" user "Package Geometry/Place Bound Top")
		(29 "B.CrtYd" user "Package Geometry/Place Bound Bottom")
		(35 "F.Fab" user "Ref Des/Assembly Top")
		(33 "B.Fab" user "Ref Des/Assembly Bottom")
	)
	(footprint ""
		(layer "F.Cu")
		(at 369.085114 -6.089904 180)
		(property "Reference" "CONX8"
			(at 0 0 180)
			(layer "F.SilkS")
			(hide yes)
			(effects
				(font
					(size 1.27 1.27)
				)
			)
		)
		(property "Value" "*"
			(at -14.3129 -7.5565 180)
			(unlocked yes)
			(layer "F.Fab")
			(hide yes)
			(effects
				(font
					(size 1.27 1.016)
					(thickness 0.1524)
				)
			)
		)
		(property "Device Type" "SMC-CONN60A-22-GP_CONN-G7-SMC-A"
			(at -14.3129 -9.0805 180)
			(unlocked yes)
			(layer "F.Fab")
			(hide yes)
			(effects
				(font
					(size 1.27 1.016)
					(thickness 0.1524)
				)
			)
		)
		(duplicate_pad_numbers_are_jumpers no)
		(pad "" np_thru_hole circle
			(at -13.10005 1.500124 180)
			(size 0.254 0.254)
			(drill 1.27)
			(layers "*.Cu" "*.Mask")
			(clearance 0.8636)
			(thermal_gap 0.8636)
		)
		(pad "" np_thru_hole circle
			(at 13.10005 0 180)
			(size 0.254 0.254)
			(drill 1.27)
			(layers "*.Cu" "*.Mask")
			(clearance 0.8636)
			(thermal_gap 0.8636)
		)
		(pad "1" smd rect
			(at -11.599926 1.700022 180)
			(size 0.508 1.1938)
			(layers "F.Cu" "F.Mask" "F.Paste")
			(net "GND")
		)
		(pad "2" smd rect
			(at -11.599926 -1.700022 180)
			(size 0.508 1.1938)
			(layers "F.Cu" "F.Mask" "F.Paste")
			(net "Net_545")
		)
		(pad "3" smd rect
			(at -10.80008 1.700022 180)
			(size 0.508 1.1938)
			(layers "F.Cu" "F.Mask" "F.Paste")
			(net "P3E_CPU0_PE2_SS_C_TXN<8>")
		)
		(pad "4" smd rect
			(at -10.80008 -1.700022 180)
			(size 0.508 1.1938)
			(layers "F.Cu" "F.Mask" "F.Paste")
			(net "GND")
		)
		(pad "5" smd rect
			(at -9.99998 1.700022 180)
			(size 0.508 1.1938)
			(layers "F.Cu" "F.Mask" "F.Paste")
			(net "P3E_CPU0_PE2_SS_C_TXP<8>")
		)
		(pad "6" smd rect
			(at -9.99998 -1.700022 180)
			(size 0.508 1.1938)
			(layers "F.Cu" "F.Mask" "F.Paste")
			(net "P3E_CPU0_PE2_SS_RXN<8>")
		)
		(pad "7" smd rect
			(at -9.19988 1.700022 180)
			(size 0.508 1.1938)
			(layers "F.Cu" "F.Mask" "F.Paste")
			(net "GND")
		)
		(pad "8" smd rect
			(at -9.19988 -1.700022 180)
			(size 0.508 1.1938)
			(layers "F.Cu" "F.Mask" "F.Paste")
			(net "P3E_CPU0_PE2_SS_RXP<8>")
		)
		(pad "9" smd rect
			(at -8.400034 1.700022 180)
			(size 0.508 1.1938)
			(layers "F.Cu" "F.Mask" "F.Paste")
			(net "P3E_CPU0_PE2_SS_C_TXN<9>")
		)
		(pad "10" smd rect
			(at -8.400034 -1.700022 180)
			(size 0.508 1.1938)
			(layers "F.Cu" "F.Mask" "F.Paste")
			(net "GND")
		)
		(pad "11" smd rect
			(at -7.599934 1.700022 180)
			(size 0.508 1.1938)
			(layers "F.Cu" "F.Mask" "F.Paste")
			(net "P3E_CPU0_PE2_SS_C_TXP<9>")
		)
		(pad "12" smd rect
			(at -7.599934 -1.700022 180)
			(size 0.508 1.1938)
			(layers "F.Cu" "F.Mask" "F.Paste")
			(net "P3E_CPU0_PE2_SS_RXN<9>")
		)
		(pad "13" smd rect
			(at -6.800088 1.700022 180)
			(size 0.508 1.1938)
			(layers "F.Cu" "F.Mask" "F.Paste")
			(net "GND")
		)
		(pad "14" smd rect
			(at -6.800088 -1.700022 180)
			(size 0.508 1.1938)
			(layers "F.Cu" "F.Mask" "F.Paste")
			(net "P3E_CPU0_PE2_SS_RXP<9>")
		)
		(pad "15" smd rect
			(at -5.999988 1.700022 180)
			(size 0.508 1.1938)
			(layers "F.Cu" "F.Mask" "F.Paste")
			(net "P3E_CPU0_PE2_SS_C_TXN<10>")
		)
		(pad "16" smd rect
			(at -5.999988 -1.700022 180)
			(size 0.508 1.1938)
			(layers "F.Cu" "F.Mask" "F.Paste")
			(net "GND")
		)
		(pad "17" smd rect
			(at -5.199888 1.700022 180)
			(size 0.508 1.1938)
			(layers "F.Cu" "F.Mask" "F.Paste")
			(net "P3E_CPU0_PE2_SS_C_TXP<10>")
		)
		(pad "18" smd rect
			(at -5.199888 -1.700022 180)
			(size 0.508 1.1938)
			(layers "F.Cu" "F.Mask" "F.Paste")
			(net "P3E_CPU0_PE2_SS_RXN<10>")
		)
		(pad "19" smd rect
			(at -4.400042 1.700022 180)
			(size 0.508 1.1938)
			(layers "F.Cu" "F.Mask" "F.Paste")
			(net "GND")
		)
		(pad "20" smd rect
			(at -4.400042 -1.700022 180)
			(size 0.508 1.1938)
			(layers "F.Cu" "F.Mask" "F.Paste")
			(net "P3E_CPU0_PE2_SS_RXP<10>")
		)
		(pad "21" smd rect
			(at -3.599942 1.700022 180)
			(size 0.508 1.1938)
			(layers "F.Cu" "F.Mask" "F.Paste")
			(net "P3E_CPU0_PE2_SS_C_TXP<11>")
		)
		(pad "22" smd rect
			(at -3.599942 -1.700022 180)
			(size 0.508 1.1938)
			(layers "F.Cu" "F.Mask" "F.Paste")
			(net "GND")
		)
		(pad "23" smd rect
			(at -2.800096 1.700022 180)
			(size 0.508 1.1938)
			(layers "F.Cu" "F.Mask" "F.Paste")
			(net "P3E_CPU0_PE2_SS_C_TXN<11>")
		)
		(pad "24" smd rect
			(at -2.800096 -1.700022 180)
			(size 0.508 1.1938)
			(layers "F.Cu" "F.Mask" "F.Paste")
			(net "P3E_CPU0_PE2_SS_RXN<11>")
		)
		(pad "25" smd rect
			(at -1.999996 1.700022 180)
			(size 0.508 1.1938)
			(layers "F.Cu" "F.Mask" "F.Paste")
			(net "GND")
		)
		(pad "26" smd rect
			(at -1.999996 -1.700022 180)
			(size 0.508 1.1938)
			(layers "F.Cu" "F.Mask" "F.Paste")
			(net "P3E_CPU0_PE2_SS_RXP<11>")
		)
		(pad "27" smd rect
			(at -1.199896 1.700022 180)
			(size 0.508 1.1938)
			(layers "F.Cu" "F.Mask" "F.Paste")
			(net "P3E_CPU0_PE2_SS_C_TXN<12>")
		)
		(pad "28" smd rect
			(at -1.199896 -1.700022 180)
			(size 0.508 1.1938)
			(layers "F.Cu" "F.Mask" "F.Paste")
			(net "GND")
		)
		(pad "29" smd rect
			(at -0.40005 1.700022 180)
			(size 0.508 1.1938)
			(layers "F.Cu" "F.Mask" "F.Paste")
			(net "P3E_CPU0_PE2_SS_C_TXP<12>")
		)
		(pad "30" smd rect
			(at -0.40005 -1.700022 180)
			(size 0.508 1.1938)
			(layers "F.Cu" "F.Mask" "F.Paste")
			(net "P3E_CPU0_PE2_SS_RXN<12>")
		)
		(pad "31" smd rect
			(at 0.40005 1.700022 180)
			(size 0.508 1.1938)
			(layers "F.Cu" "F.Mask" "F.Paste")
			(net "GND")
		)
		(pad "32" smd rect
			(at 0.40005 -1.700022 180)
			(size 0.508 1.1938)
			(layers "F.Cu" "F.Mask" "F.Paste")
			(net "P3E_CPU0_PE2_SS_RXP<12>")
		)
		(pad "33" smd rect
			(at 1.199896 1.700022 180)
			(size 0.508 1.1938)
			(layers "F.Cu" "F.Mask" "F.Paste")
			(net "P3E_CPU0_PE2_SS_C_TXN<13>")
		)
		(pad "34" smd rect
			(at 1.199896 -1.700022 180)
			(size 0.508 1.1938)
			(layers "F.Cu" "F.Mask" "F.Paste")
			(net "GND")
		)
		(pad "35" smd rect
			(at 1.999996 1.700022 180)
			(size 0.508 1.1938)
			(layers "F.Cu" "F.Mask" "F.Paste")
			(net "P3E_CPU0_PE2_SS_C_TXP<13>")
		)
		(pad "36" smd rect
			(at 1.999996 -1.700022 180)
			(size 0.508 1.1938)
			(layers "F.Cu" "F.Mask" "F.Paste")
			(net "P3E_CPU0_PE2_SS_RXP<13>")
		)
		(pad "37" smd rect
			(at 2.800096 1.700022 180)
			(size 0.508 1.1938)
			(layers "F.Cu" "F.Mask" "F.Paste")
			(net "GND")
		)
		(pad "38" smd rect
			(at 2.800096 -1.700022 180)
			(size 0.508 1.1938)
			(layers "F.Cu" "F.Mask" "F.Paste")
			(net "P3E_CPU0_PE2_SS_RXN<13>")
		)
		(pad "39" smd rect
			(at 3.599942 1.700022 180)
			(size 0.508 1.1938)
			(layers "F.Cu" "F.Mask" "F.Paste")
			(net "P3E_CPU0_PE2_SS_C_TXP<14>")
		)
		(pad "40" smd rect
			(at 3.599942 -1.700022 180)
			(size 0.508 1.1938)
			(layers "F.Cu" "F.Mask" "F.Paste")
			(net "GND")
		)
		(pad "41" smd rect
			(at 4.400042 1.700022 180)
			(size 0.508 1.1938)
			(layers "F.Cu" "F.Mask" "F.Paste")
			(net "P3E_CPU0_PE2_SS_C_TXN<14>")
		)
	)
)
